# BASEBOARD_FAB2 (Tioga Pass) — schematic netlist excerpt (pin names and nets, part order shuffled) for the footprints in the layout excerpt that follows; sources: Cadence DE-HDL packaged netlist, KiCad conversion of Wiwynn_Tioga_Pass_MB.brd

R2T35  RES  4.75K 1% CHIP  pkg 0402  page 156 : A = P3V3_STBY ; B = RST_BMC_SYSRST_BTN_OUT_N
C7L4  CAP_A  47UF 4V 20% X5R  pkg 0603V  page 228 : A = PVDDQ_KLM ; B = GND
R1L27  RES  4.75K 1% CHIP  pkg 0402  page 175 : A = P3V3_STBY ; B = FP_PWR_BTN_R_N

(kicad_pcb
	(version 20260206)
	(generator "pcbnew")
	(generator_version "10.0")
	(general
		(thickness 1.6)
		(legacy_teardrops no)
	)
	(paper "A4")
	(title_block
		(title "Wiwynn_Tioga_Pass_MB.brd")
		(comment 1 "Tioga Pass / footprints 3465-3467 of 4770")
	)
	(layers
		(0 "F.Cu" signal "TOP")
		(4 "In1.Cu" signal "L2GND")
		(6 "In2.Cu" signal "L3")
		(8 "In3.Cu" signal "L4GND")
		(10 "In4.Cu" signal "L5")
		(12 "In5.Cu" signal "L6GND")
		(14 "In6.Cu" signal "L7VCC")
		(16 "In7.Cu" signal "L8VCC")
		(18 "In8.Cu" signal "L9GND")
		(20 "In9.Cu" signal "L10")
		(22 "In10.Cu" signal "L11GND")
		(24 "In11.Cu" signal "L12")
		(26 "In12.Cu" signal "L13GND")
		(2 "B.Cu" signal "BOTTOM")
		(9 "F.Adhes" user "F.Adhesive")
		(11 "B.Adhes" user "B.Adhesive")
		(13 "F.Paste" user "Package Geometry/Pastemask Top")
		(15 "B.Paste" user "Package Geometry/Pastemask Bottom")
		(5 "F.SilkS" user "Ref Des/Silkscreen Top")
		(7 "B.SilkS" user "Ref Des/Silkscreen Bottom")
		(1 "F.Mask" user "Board Geometry/Soldermask Top")
		(3 "B.Mask" user "Board Geometry/Soldermask Bottom")
		(17 "Dwgs.User" user "User.Drawings")
		(19 "Cmts.User" user "User.Comments")
		(21 "Eco1.User" user "User.Eco1")
		(23 "Eco2.User" user "User.Eco2")
		(25 "Edge.Cuts" user "Board Geometry/Outline")
		(27 "Margin" user)
		(31 "F.CrtYd" user "Package Geometry/Place Bound Top")
		(29 "B.CrtYd" user "Package Geometry/Place Bound Bottom")
		(35 "F.Fab" user "Ref Des/Assembly Top")
		(33 "B.Fab" user "Ref Des/Assembly Bottom")
	)
	(footprint ""
		(layer "B.Cu")
		(at 111.000032 -145.0086 90)
		(property "Reference" "C7L4"
			(at -1.848866 0.752348 90)
			(unlocked yes)
			(layer "B.SilkS")
			(effects
				(font
					(size 1.27 0.9652)
					(thickness 0.1524)
				)
				(justify mirror)
			)
		)
		(property "Value" ""
			(at 0 0 90)
			(layer "B.Fab")
			(effects
				(font
					(size 1.27 1.27)
				)
				(justify mirror)
			)
		)
		(duplicate_pad_numbers_are_jumpers no)
		(fp_rect
			(start 0.500126 1.598422)
			(end -0.500126 -0.201422)
			(stroke
				(width 0)
				(type default)
			)
			(fill no)
			(layer "B.CrtYd")
		)
		(fp_line
			(start 0.500126 -0.201422)
			(end -0.500126 -0.201422)
			(stroke
				(width 0.1)
				(type default)
			)
			(layer "B.Fab")
		)
		(fp_line
			(start -0.500126 -0.201422)
			(end -0.500126 1.598422)
			(stroke
				(width 0.1)
				(type default)
			)
			(layer "B.Fab")
		)
		(fp_line
			(start 0.500126 1.598422)
			(end 0.500126 -0.201422)
			(stroke
				(width 0.1)
				(type default)
			)
			(layer "B.Fab")
		)
		(fp_line
			(start -0.500126 1.598422)
			(end 0.500126 1.598422)
			(stroke
				(width 0.1)
				(type default)
			)
			(layer "B.Fab")
		)
		(pad "1" smd rect
			(at 0 0)
			(size 0.889 0.9906)
			(layers "B.Cu" "B.Mask" "B.Paste")
			(net "PVDDQ_KLM")
		)
		(pad "2" smd rect
			(at 0 1.397)
			(size 0.889 0.9906)
			(layers "B.Cu" "B.Mask" "B.Paste")
			(net "GND")
		)
		(zone
			(layer "B.Cu")
			(hatch none 0.5)
			(connect_pads
				(clearance 0)
			)
			(min_thickness 0.25)
			(keepout
				(tracks allowed)
				(vias not_allowed)
				(pads allowed)
				(copperpour not_allowed)
				(footprints allowed)
			)
			(placement
				(enabled no)
				(sheetname "")
			)
			(fill
				(thermal_gap 0.5)
				(thermal_bridge_width 0.5)
				(island_removal_mode 0)
			)
			(polygon
				(pts
					(xy 111.952532 -145.5039) (xy 111.444532 -145.5039) (xy 111.444532 -144.5133) (xy 111.952532 -144.5133)
				)
			)
		)
		(zone
			(layer "B.Cu")
			(hatch none 0.5)
			(connect_pads
				(clearance 0)
			)
			(min_thickness 0.25)
			(keepout
				(tracks not_allowed)
				(vias allowed)
				(pads allowed)
				(copperpour not_allowed)
				(footprints allowed)
			)
			(placement
				(enabled no)
				(sheetname "")
			)
			(fill
				(thermal_gap 0.5)
				(thermal_bridge_width 0.5)
				(island_removal_mode 0)
			)
			(polygon
				(pts
					(xy 111.952532 -145.5039) (xy 111.444532 -145.5039) (xy 111.444532 -144.5133) (xy 111.952532 -144.5133)
				)
			)
		)
	)
	(footprint ""
		(layer "B.Cu")
		(at 397.886174 -33.262316)
		(property "Reference" "R2T35"
			(at 0 0 0)
			(layer "B.SilkS")
			(hide yes)
			(effects
				(font
					(size 1.27 1.27)
				)
				(justify mirror)
			)
		)
		(property "Value" ""
			(at 0 0 0)
			(layer "B.Fab")
			(effects
				(font
					(size 1.27 1.27)
				)
				(justify mirror)
			)
		)
		(duplicate_pad_numbers_are_jumpers no)
		(fp_poly
			(pts
				(xy 0.2794 -0.1016) (xy -0.2794 -0.1016) (xy -0.2794 0.9906) (xy 0.2794 0.9906)
			)
			(stroke
				(width 0)
				(type default)
			)
			(fill no)
			(layer "B.CrtYd")
		)
		(fp_line
			(start -0.2794 -0.1016)
			(end 0.2794 -0.1016)
			(stroke
				(width 0.1)
				(type default)
			)
			(layer "B.Fab")
		)
		(fp_line
			(start -0.2794 0.9906)
			(end -0.2794 -0.1016)
			(stroke
				(width 0.1)
				(type default)
			)
			(layer "B.Fab")
		)
		(fp_line
			(start 0.2794 -0.1016)
			(end 0.2794 0.9906)
			(stroke
				(width 0.1)
				(type default)
			)
			(layer "B.Fab")
		)
		(fp_line
			(start 0.2794 0.9906)
			(end -0.2794 0.9906)
			(stroke
				(width 0.1)
				(type default)
			)
			(layer "B.Fab")
		)
		(pad "1" smd rect
			(at 0 0 180)
			(size 0.508 0.508)
			(layers "B.Cu" "B.Mask" "B.Paste")
			(net "P3V3_STBY")
		)
		(pad "2" smd rect
			(at 0 0.889 180)
			(size 0.508 0.508)
			(layers "B.Cu" "B.Mask" "B.Paste")
			(net "RST_BMC_SYSRST_BTN_OUT_N")
		)
		(zone
			(layer "B.Cu")
			(hatch none 0.5)
			(connect_pads
				(clearance 0)
			)
			(min_thickness 0.25)
			(keepout
				(tracks allowed)
				(vias not_allowed)
				(pads allowed)
				(copperpour not_allowed)
				(footprints allowed)
			)
			(placement
				(enabled no)
				(sheetname "")
			)
			(fill
				(thermal_gap 0.5)
				(thermal_bridge_width 0.5)
				(island_removal_mode 0)
			)
			(polygon
				(pts
					(xy 398.140174 -33.008316) (xy 397.632174 -33.008316) (xy 397.632174 -32.627316) (xy 398.140174 -32.627316)
				)
			)
		)
		(zone
			(layer "B.Cu")
			(hatch none 0.5)
			(connect_pads
				(clearance 0)
			)
			(min_thickness 0.25)
			(keepout
				(tracks not_allowed)
				(vias allowed)
				(pads allowed)
				(copperpour not_allowed)
				(footprints allowed)
			)
			(placement
				(enabled no)
				(sheetname "")
			)
			(fill
				(thermal_gap 0.5)
				(thermal_bridge_width 0.5)
				(island_removal_mode 0)
			)
			(polygon
				(pts
					(xy 398.140174 -32.627316) (xy 397.632174 -32.627316) (xy 397.632174 -33.008316) (xy 398.140174 -33.008316)
				)
			)
		)
	)
	(footprint ""
		(layer "B.Cu")
		(at 470.4715 -138.557 90)
		(property "Reference" "R1L27"
			(at 0 0 90)
			(layer "B.SilkS")
			(hide yes)
			(effects
				(font
					(size 1.27 1.27)
				)
				(justify mirror)
			)
		)
		(property "Value" ""
			(at 0 0 90)
			(layer "B.Fab")
			(effects
				(font
					(size 1.27 1.27)
				)
				(justify mirror)
			)
		)
		(duplicate_pad_numbers_are_jumpers no)
		(fp_poly
			(pts
				(xy 0.2794 -0.1016) (xy -0.2794 -0.1016) (xy -0.2794 0.9906) (xy 0.2794 0.9906)
			)
			(stroke
				(width 0)
				(type default)
			)
			(fill no)
			(layer "B.CrtYd")
		)
		(fp_line
			(start 0.2794 -0.1016)
			(end 0.2794 0.9906)
			(stroke
				(width 0.1)
				(type default)
			)
			(layer "B.Fab")
		)
		(fp_line
			(start -0.2794 -0.1016)
			(end 0.2794 -0.1016)
			(stroke
				(width 0.1)
				(type default)
			)
			(layer "B.Fab")
		)
		(fp_line
			(start 0.2794 0.9906)
			(end -0.2794 0.9906)
			(stroke
				(width 0.1)
				(type default)
			)
			(layer "B.Fab")
		)
		(fp_line
			(start -0.2794 0.9906)
			(end -0.2794 -0.1016)
			(stroke
				(width 0.1)
				(type default)
			)
			(layer "B.Fab")
		)
		(pad "1" smd rect
			(at 0 0 270)
			(size 0.508 0.508)
			(layers "B.Cu" "B.Mask" "B.Paste")
			(net "P3V3_STBY")
		)
		(pad "2" smd rect
			(at 0 0.889 270)
			(size 0.508 0.508)
			(layers "B.Cu" "B.Mask" "B.Paste")
			(net "FP_PWR_BTN_R_N")
		)
		(zone
			(layer "B.Cu")
			(hatch none 0.5)
			(connect_pads
				(clearance 0)
			)
			(min_thickness 0.25)
			(keepout
				(tracks allowed)
				(vias not_allowed)
				(pads allowed)
				(copperpour not_allowed)
				(footprints allowed)
			)
			(placement
				(enabled no)
				(sheetname "")
			)
			(fill
				(thermal_gap 0.5)
				(thermal_bridge_width 0.5)
				(island_removal_mode 0)
			)
			(polygon
				(pts
					(xy 470.7255 -138.811) (xy 470.7255 -138.303) (xy 471.1065 -138.303) (xy 471.1065 -138.811)
				)
			)
		)
		(zone
			(layer "B.Cu")
			(hatch none 0.5)
			(connect_pads
				(clearance 0)
			)
			(min_thickness 0.25)
			(keepout
				(tracks not_allowed)
				(vias allowed)
				(pads allowed)
				(copperpour not_allowed)
				(footprints allowed)
			)
			(placement
				(enabled no)
				(sheetname "")
			)
			(fill
				(thermal_gap 0.5)
				(thermal_bridge_width 0.5)
				(island_removal_mode 0)
			)
			(polygon
				(pts
					(xy 471.1065 -138.811) (xy 471.1065 -138.303) (xy 470.7255 -138.303) (xy 470.7255 -138.811)
				)
			)
		)
	)
)
